# T6G (Grand Teton) — schematic netlist excerpt (pin names and nets, part order shuffled) for the footprints in the layout excerpt that follows; sources: Cadence DE-HDL packaged netlist, KiCad conversion of 04192023_DAF0TMB3IC0_F0TG_MB_C_brd_V02_OCP.brd

C936  Q_CAP_DIFFBUS  DIFF BUS_0.22UF 6.3V 20% X6S  pkg C0201  page 63 : \1\ = P5E_CPU0_P1_TX_C_DN<14> ; \2\ = P5E_CPU0_P1_TX_DN<14>
R6163  Q_RES  1K 1% EMPTY  pkg 0402LF  page 112 : A = P3V3_AUX ; B = FM_P2E_BUF2_EQB1
R1507  Q_RES  1K 1% CHIP  pkg 0402LF  page 165 : A = P3V3_AUX ; B = LED_BIOS_DBG_MODE_N

(kicad_pcb
	(version 20260206)
	(generator "pcbnew")
	(generator_version "10.0")
	(general
		(thickness 1.6)
		(legacy_teardrops no)
	)
	(paper "A4")
	(title_block
		(title "04192023_DAF0TMB3IC0_F0TG_MB_C_brd_V02_OCP.brd")
		(comment 1 "Grand Teton / footprints 1261-1263 of 8354")
	)
	(layers
		(0 "F.Cu" signal "TOP")
		(4 "In1.Cu" signal "GND")
		(6 "In2.Cu" signal "IN1")
		(8 "In3.Cu" signal "GND1")
		(10 "In4.Cu" signal "IN2")
		(12 "In5.Cu" signal "GND2")
		(14 "In6.Cu" signal "IN3")
		(16 "In7.Cu" signal "GND3")
		(18 "In8.Cu" signal "VCC")
		(20 "In9.Cu" signal "VCC1")
		(22 "In10.Cu" signal "GND4")
		(24 "In11.Cu" signal "IN4")
		(26 "In12.Cu" signal "GND5")
		(28 "In13.Cu" signal "IN5")
		(30 "In14.Cu" signal "GND6")
		(32 "In15.Cu" signal "IN6")
		(34 "In16.Cu" signal "GND7")
		(2 "B.Cu" signal "BOTTOM")
		(9 "F.Adhes" user "F.Adhesive")
		(11 "B.Adhes" user "B.Adhesive")
		(13 "F.Paste" user "Package Geometry/Pastemask Top")
		(15 "B.Paste" user "Package Geometry/Pastemask Bottom")
		(5 "F.SilkS" user "Ref Des/Silkscreen Top")
		(7 "B.SilkS" user "Ref Des/Silkscreen Bottom")
		(1 "F.Mask" user "Board Geometry/Soldermask Top")
		(3 "B.Mask" user "Board Geometry/Soldermask Bottom")
		(17 "Dwgs.User" user "User.Drawings")
		(19 "Cmts.User" user "User.Comments")
		(21 "Eco1.User" user "User.Eco1")
		(23 "Eco2.User" user "User.Eco2")
		(25 "Edge.Cuts" user "Board Geometry/Outline")
		(27 "Margin" user)
		(31 "F.CrtYd" user "Package Geometry/Place Bound Top")
		(29 "B.CrtYd" user "Package Geometry/Place Bound Bottom")
		(35 "F.Fab" user "Ref Des/Assembly Top")
		(33 "B.Fab" user "Ref Des/Assembly Bottom")
	)
	(footprint ""
		(layer "F.Cu")
		(at 20.860258 -427.580298 -90)
		(property "Reference" "R6163"
			(at 0 0 270)
			(layer "F.SilkS")
			(hide yes)
			(effects
				(font
					(size 1.27 1.27)
				)
			)
		)
		(property "Value" ""
			(at 0 0 270)
			(layer "F.Fab")
			(effects
				(font
					(size 1.27 1.27)
				)
			)
		)
		(duplicate_pad_numbers_are_jumpers no)
		(fp_line
			(start -0.7874 0.4064)
			(end -0.7874 -0.4064)
			(stroke
				(width 0.1524)
				(type default)
			)
			(layer "F.SilkS")
		)
		(fp_line
			(start 0.7874 0.4064)
			(end -0.7874 0.4064)
			(stroke
				(width 0.1524)
				(type default)
			)
			(layer "F.SilkS")
		)
		(fp_line
			(start -0.7874 -0.4064)
			(end 0.7874 -0.4064)
			(stroke
				(width 0.1524)
				(type default)
			)
			(layer "F.SilkS")
		)
		(fp_line
			(start 0.7874 -0.4064)
			(end 0.7874 0.4064)
			(stroke
				(width 0.1524)
				(type default)
			)
			(layer "F.SilkS")
		)
		(fp_line
			(start -0.67945 0.3048)
			(end -0.67945 -0.305054)
			(stroke
				(width 0.1)
				(type default)
			)
			(layer "F.Fab")
		)
		(fp_line
			(start -0.12065 0.3048)
			(end -0.67945 0.3048)
			(stroke
				(width 0.1)
				(type default)
			)
			(layer "F.Fab")
		)
		(fp_line
			(start 0.120396 0.3048)
			(end 0.120396 0.2794)
			(stroke
				(width 0.1)
				(type default)
			)
			(layer "F.Fab")
		)
		(fp_line
			(start 0.67945 0.3048)
			(end 0.120396 0.3048)
			(stroke
				(width 0.1)
				(type default)
			)
			(layer "F.Fab")
		)
		(fp_line
			(start -0.12065 0.2794)
			(end -0.12065 0.3048)
			(stroke
				(width 0.1)
				(type default)
			)
			(layer "F.Fab")
		)
		(fp_line
			(start 0.120396 0.2794)
			(end -0.12065 0.2794)
			(stroke
				(width 0.1)
				(type default)
			)
			(layer "F.Fab")
		)
		(fp_line
			(start -0.12065 -0.2794)
			(end 0.12065 -0.2794)
			(stroke
				(width 0.1)
				(type default)
			)
			(layer "F.Fab")
		)
		(fp_line
			(start 0.12065 -0.2794)
			(end 0.12065 -0.3048)
			(stroke
				(width 0.1)
				(type default)
			)
			(layer "F.Fab")
		)
		(fp_line
			(start 0.12065 -0.3048)
			(end 0.67945 -0.3048)
			(stroke
				(width 0.1)
				(type default)
			)
			(layer "F.Fab")
		)
		(fp_line
			(start 0.67945 -0.3048)
			(end 0.67945 0.3048)
			(stroke
				(width 0.1)
				(type default)
			)
			(layer "F.Fab")
		)
		(fp_line
			(start -0.67945 -0.305054)
			(end -0.12065 -0.305054)
			(stroke
				(width 0.1)
				(type default)
			)
			(layer "F.Fab")
		)
		(fp_line
			(start -0.12065 -0.305054)
			(end -0.12065 -0.2794)
			(stroke
				(width 0.1)
				(type default)
			)
			(layer "F.Fab")
		)
		(pad "1" smd circle
			(at -0.40005 0 270)
			(size 0 0)
			(layers "F.Cu" "F.Mask" "F.Paste")
			(net "P3V3_AUX")
		)
		(pad "2" smd circle
			(at 0.40005 0 270)
			(size 0 0)
			(layers "F.Cu" "F.Mask" "F.Paste")
			(net "FM_P2E_BUF2_EQB1")
		)
	)
	(footprint ""
		(layer "F.Cu")
		(at 358.268524 -384.449828)
		(property "Reference" "C936"
			(at 0 0 0)
			(layer "F.SilkS")
			(hide yes)
			(effects
				(font
					(size 1.27 1.27)
				)
			)
		)
		(property "Value" ""
			(at 0 0 0)
			(layer "F.Fab")
			(effects
				(font
					(size 1.27 1.27)
				)
			)
		)
		(duplicate_pad_numbers_are_jumpers no)
		(fp_line
			(start -0.299974 -0.150114)
			(end 0.299974 -0.150114)
			(stroke
				(width 0.1)
				(type default)
			)
			(layer "F.Fab")
		)
		(fp_line
			(start -0.299974 0.150114)
			(end -0.299974 -0.150114)
			(stroke
				(width 0.1)
				(type default)
			)
			(layer "F.Fab")
		)
		(fp_line
			(start 0.299974 -0.150114)
			(end 0.299974 0.150114)
			(stroke
				(width 0.1)
				(type default)
			)
			(layer "F.Fab")
		)
		(fp_line
			(start 0.299974 0.150114)
			(end -0.299974 0.150114)
			(stroke
				(width 0.1)
				(type default)
			)
			(layer "F.Fab")
		)
		(pad "1" smd rect
			(at -0.2667 0)
			(size 0.3048 0.381)
			(layers "F.Cu" "F.Mask" "F.Paste")
			(net "P5E_CPU0_P1_TX_C_DN<14>")
		)
		(pad "2" smd rect
			(at 0.2667 0)
			(size 0.3048 0.381)
			(layers "F.Cu" "F.Mask" "F.Paste")
			(net "P5E_CPU0_P1_TX_DN<14>")
		)
	)
	(footprint ""
		(layer "F.Cu")
		(at 338.683346 -23.897336 -90)
		(property "Reference" "R1507"
			(at 0 0 270)
			(layer "F.SilkS")
			(hide yes)
			(effects
				(font
					(size 1.27 1.27)
				)
			)
		)
		(property "Value" ""
			(at 0 0 270)
			(layer "F.Fab")
			(effects
				(font
					(size 1.27 1.27)
				)
			)
		)
		(duplicate_pad_numbers_are_jumpers no)
		(fp_line
			(start -0.7874 0.4064)
			(end -0.7874 -0.4064)
			(stroke
				(width 0.1524)
				(type default)
			)
			(layer "F.SilkS")
		)
		(fp_line
			(start 0.7874 0.4064)
			(end -0.7874 0.4064)
			(stroke
				(width 0.1524)
				(type default)
			)
			(layer "F.SilkS")
		)
		(fp_line
			(start -0.7874 -0.4064)
			(end 0.7874 -0.4064)
			(stroke
				(width 0.1524)
				(type default)
			)
			(layer "F.SilkS")
		)
		(fp_line
			(start 0.7874 -0.4064)
			(end 0.7874 0.4064)
			(stroke
				(width 0.1524)
				(type default)
			)
			(layer "F.SilkS")
		)
		(fp_line
			(start -0.67945 0.3048)
			(end -0.67945 -0.305054)
			(stroke
				(width 0.1)
				(type default)
			)
			(layer "F.Fab")
		)
		(fp_line
			(start -0.12065 0.3048)
			(end -0.67945 0.3048)
			(stroke
				(width 0.1)
				(type default)
			)
			(layer "F.Fab")
		)
		(fp_line
			(start 0.120396 0.3048)
			(end 0.120396 0.2794)
			(stroke
				(width 0.1)
				(type default)
			)
			(layer "F.Fab")
		)
		(fp_line
			(start 0.67945 0.3048)
			(end 0.120396 0.3048)
			(stroke
				(width 0.1)
				(type default)
			)
			(layer "F.Fab")
		)
		(fp_line
			(start -0.12065 0.2794)
			(end -0.12065 0.3048)
			(stroke
				(width 0.1)
				(type default)
			)
			(layer "F.Fab")
		)
		(fp_line
			(start 0.120396 0.2794)
			(end -0.12065 0.2794)
			(stroke
				(width 0.1)
				(type default)
			)
			(layer "F.Fab")
		)
		(fp_line
			(start -0.12065 -0.2794)
			(end 0.12065 -0.2794)
			(stroke
				(width 0.1)
				(type default)
			)
			(layer "F.Fab")
		)
		(fp_line
			(start 0.12065 -0.2794)
			(end 0.12065 -0.3048)
			(stroke
				(width 0.1)
				(type default)
			)
			(layer "F.Fab")
		)
		(fp_line
			(start 0.12065 -0.3048)
			(end 0.67945 -0.3048)
			(stroke
				(width 0.1)
				(type default)
			)
			(layer "F.Fab")
		)
		(fp_line
			(start 0.67945 -0.3048)
			(end 0.67945 0.3048)
			(stroke
				(width 0.1)
				(type default)
			)
			(layer "F.Fab")
		)
		(fp_line
			(start -0.67945 -0.305054)
			(end -0.12065 -0.305054)
			(stroke
				(width 0.1)
				(type default)
			)
			(layer "F.Fab")
		)
		(fp_line
			(start -0.12065 -0.305054)
			(end -0.12065 -0.2794)
			(stroke
				(width 0.1)
				(type default)
			)
			(layer "F.Fab")
		)
		(pad "1" smd circle
			(at -0.40005 0 270)
			(size 0 0)
			(layers "F.Cu" "F.Mask" "F.Paste")
			(net "P3V3_AUX")
		)
		(pad "2" smd circle
			(at 0.40005 0 270)
			(size 0 0)
			(layers "F.Cu" "F.Mask" "F.Paste")
			(net "LED_BIOS_DBG_MODE_N")
		)
	)
)
